# T6G (Grand Teton) — schematic netlist excerpt (pin names and nets, part order shuffled) for the footprints in the layout excerpt that follows; sources: Cadence DE-HDL packaged netlist, KiCad conversion of 04192023_DAF0TMB3IC0_F0TG_MB_C_brd_V02_OCP.brd

PC6560  Q_CAP  22UF 16V 20% X6S  pkg C0805  page 363 : A = SW_P12V_AUX_P0V9_RETIMER_CPU0_FLT ; B = GND
C2653  Q_CAP  22UF 4V 20% X6S  pkg C0402  page 70 : A = PVDD11_S3_P0 ; B = GND
R8036  Q_RES  4.7K 5% EMPTY  pkg 0402LF  page 153 : A = PVDD18_S5_P0 ; B = ESPI_CPU0_ALERT_PLD_N

(kicad_pcb
	(version 20260206)
	(generator "pcbnew")
	(generator_version "10.0")
	(general
		(thickness 1.6)
		(legacy_teardrops no)
	)
	(paper "A4")
	(title_block
		(title "04192023_DAF0TMB3IC0_F0TG_MB_C_brd_V02_OCP.brd")
		(comment 1 "Grand Teton / footprints 8241-8243 of 8354")
	)
	(layers
		(0 "F.Cu" signal "TOP")
		(4 "In1.Cu" signal "GND")
		(6 "In2.Cu" signal "IN1")
		(8 "In3.Cu" signal "GND1")
		(10 "In4.Cu" signal "IN2")
		(12 "In5.Cu" signal "GND2")
		(14 "In6.Cu" signal "IN3")
		(16 "In7.Cu" signal "GND3")
		(18 "In8.Cu" signal "VCC")
		(20 "In9.Cu" signal "VCC1")
		(22 "In10.Cu" signal "GND4")
		(24 "In11.Cu" signal "IN4")
		(26 "In12.Cu" signal "GND5")
		(28 "In13.Cu" signal "IN5")
		(30 "In14.Cu" signal "GND6")
		(32 "In15.Cu" signal "IN6")
		(34 "In16.Cu" signal "GND7")
		(2 "B.Cu" signal "BOTTOM")
		(9 "F.Adhes" user "F.Adhesive")
		(11 "B.Adhes" user "B.Adhesive")
		(13 "F.Paste" user "Package Geometry/Pastemask Top")
		(15 "B.Paste" user "Package Geometry/Pastemask Bottom")
		(5 "F.SilkS" user "Ref Des/Silkscreen Top")
		(7 "B.SilkS" user "Ref Des/Silkscreen Bottom")
		(1 "F.Mask" user "Board Geometry/Soldermask Top")
		(3 "B.Mask" user "Board Geometry/Soldermask Bottom")
		(17 "Dwgs.User" user "User.Drawings")
		(19 "Cmts.User" user "User.Comments")
		(21 "Eco1.User" user "User.Eco1")
		(23 "Eco2.User" user "User.Eco2")
		(25 "Edge.Cuts" user "Board Geometry/Outline")
		(27 "Margin" user)
		(31 "F.CrtYd" user "Package Geometry/Place Bound Top")
		(29 "B.CrtYd" user "Package Geometry/Place Bound Bottom")
		(35 "F.Fab" user "Ref Des/Assembly Top")
		(33 "B.Fab" user "Ref Des/Assembly Bottom")
	)
	(footprint ""
		(layer "B.Cu")
		(at 182.499 -145.542 90)
		(property "Reference" "R8036"
			(at 0 0 90)
			(layer "B.SilkS")
			(hide yes)
			(effects
				(font
					(size 1.27 1.27)
				)
				(justify mirror)
			)
		)
		(property "Value" ""
			(at 0 0 90)
			(layer "B.Fab")
			(effects
				(font
					(size 1.27 1.27)
				)
				(justify mirror)
			)
		)
		(duplicate_pad_numbers_are_jumpers no)
		(fp_line
			(start 0.7874 -0.4064)
			(end -0.7874 -0.4064)
			(stroke
				(width 0.1524)
				(type default)
			)
			(layer "B.SilkS")
		)
		(fp_line
			(start -0.7874 -0.4064)
			(end -0.7874 0.4064)
			(stroke
				(width 0.1524)
				(type default)
			)
			(layer "B.SilkS")
		)
		(fp_line
			(start 0.7874 0.4064)
			(end 0.7874 -0.4064)
			(stroke
				(width 0.1524)
				(type default)
			)
			(layer "B.SilkS")
		)
		(fp_line
			(start -0.7874 0.4064)
			(end 0.7874 0.4064)
			(stroke
				(width 0.1524)
				(type default)
			)
			(layer "B.SilkS")
		)
		(fp_line
			(start 0.67945 -0.305054)
			(end 0.12065 -0.305054)
			(stroke
				(width 0.1)
				(type default)
			)
			(layer "B.Fab")
		)
		(fp_line
			(start 0.12065 -0.305054)
			(end 0.12065 -0.2794)
			(stroke
				(width 0.1)
				(type default)
			)
			(layer "B.Fab")
		)
		(fp_line
			(start -0.12065 -0.3048)
			(end -0.67945 -0.3048)
			(stroke
				(width 0.1)
				(type default)
			)
			(layer "B.Fab")
		)
		(fp_line
			(start -0.67945 -0.3048)
			(end -0.67945 0.3048)
			(stroke
				(width 0.1)
				(type default)
			)
			(layer "B.Fab")
		)
		(fp_line
			(start 0.12065 -0.2794)
			(end -0.12065 -0.2794)
			(stroke
				(width 0.1)
				(type default)
			)
			(layer "B.Fab")
		)
		(fp_line
			(start -0.12065 -0.2794)
			(end -0.12065 -0.3048)
			(stroke
				(width 0.1)
				(type default)
			)
			(layer "B.Fab")
		)
		(fp_line
			(start 0.12065 0.2794)
			(end 0.12065 0.3048)
			(stroke
				(width 0.1)
				(type default)
			)
			(layer "B.Fab")
		)
		(fp_line
			(start -0.120396 0.2794)
			(end 0.12065 0.2794)
			(stroke
				(width 0.1)
				(type default)
			)
			(layer "B.Fab")
		)
		(fp_line
			(start 0.67945 0.3048)
			(end 0.67945 -0.305054)
			(stroke
				(width 0.1)
				(type default)
			)
			(layer "B.Fab")
		)
		(fp_line
			(start 0.12065 0.3048)
			(end 0.67945 0.3048)
			(stroke
				(width 0.1)
				(type default)
			)
			(layer "B.Fab")
		)
		(fp_line
			(start -0.120396 0.3048)
			(end -0.120396 0.2794)
			(stroke
				(width 0.1)
				(type default)
			)
			(layer "B.Fab")
		)
		(fp_line
			(start -0.67945 0.3048)
			(end -0.120396 0.3048)
			(stroke
				(width 0.1)
				(type default)
			)
			(layer "B.Fab")
		)
		(pad "1" smd circle
			(at 0.40005 0 270)
			(size 0 0)
			(layers "B.Cu" "B.Mask" "B.Paste")
			(net "PVDD18_S5_P0")
		)
		(pad "2" smd circle
			(at -0.40005 0 270)
			(size 0 0)
			(layers "B.Cu" "B.Mask" "B.Paste")
			(net "ESPI_CPU0_ALERT_PLD_N")
		)
	)
	(footprint ""
		(layer "B.Cu")
		(at 447.237866 -405.7777)
		(property "Reference" "PC6560"
			(at 0 0 0)
			(layer "B.SilkS")
			(hide yes)
			(effects
				(font
					(size 1.27 1.27)
				)
				(justify mirror)
			)
		)
		(property "Value" ""
			(at 0 0 0)
			(layer "B.Fab")
			(effects
				(font
					(size 1.27 1.27)
				)
				(justify mirror)
			)
		)
		(duplicate_pad_numbers_are_jumpers no)
		(fp_line
			(start -1.524 -0.762)
			(end -1.524 0.762)
			(stroke
				(width 0.1524)
				(type default)
			)
			(layer "B.SilkS")
		)
		(fp_line
			(start -1.524 0.762)
			(end 1.524 0.762)
			(stroke
				(width 0.1524)
				(type default)
			)
			(layer "B.SilkS")
		)
		(fp_line
			(start 1.524 -0.762)
			(end -1.524 -0.762)
			(stroke
				(width 0.1524)
				(type default)
			)
			(layer "B.SilkS")
		)
		(fp_line
			(start 1.524 0.762)
			(end 1.524 -0.762)
			(stroke
				(width 0.1524)
				(type default)
			)
			(layer "B.SilkS")
		)
		(fp_line
			(start -1.1049 -0.724916)
			(end 1.1049 -0.724916)
			(stroke
				(width 0.1)
				(type default)
			)
			(layer "B.Fab")
		)
		(fp_line
			(start -1.1049 0.724916)
			(end -1.1049 -0.724916)
			(stroke
				(width 0.1)
				(type default)
			)
			(layer "B.Fab")
		)
		(fp_line
			(start 1.1049 -0.724916)
			(end 1.1049 0.724916)
			(stroke
				(width 0.1)
				(type default)
			)
			(layer "B.Fab")
		)
		(fp_line
			(start 1.1049 0.724916)
			(end -1.1049 0.724916)
			(stroke
				(width 0.1)
				(type default)
			)
			(layer "B.Fab")
		)
		(pad "1" smd rect
			(at 0.889 0)
			(size 1.016 1.27)
			(layers "B.Cu" "B.Mask" "B.Paste")
			(net "SW_P12V_AUX_P0V9_RETIMER_CPU0_FLT")
		)
		(pad "2" smd rect
			(at -0.889 0)
			(size 1.016 1.27)
			(layers "B.Cu" "B.Mask" "B.Paste")
			(net "GND")
		)
	)
	(footprint ""
		(layer "B.Cu")
		(at 365.709454 -264.35431)
		(property "Reference" "C2653"
			(at 0 0 0)
			(layer "B.SilkS")
			(hide yes)
			(effects
				(font
					(size 1.27 1.27)
				)
				(justify mirror)
			)
		)
		(property "Value" ""
			(at 0 0 0)
			(layer "B.Fab")
			(effects
				(font
					(size 1.27 1.27)
				)
				(justify mirror)
			)
		)
		(duplicate_pad_numbers_are_jumpers no)
		(fp_line
			(start -0.7874 -0.4064)
			(end -0.7874 0.4064)
			(stroke
				(width 0.1524)
				(type default)
			)
			(layer "B.SilkS")
		)
		(fp_line
			(start -0.7874 0.4064)
			(end 0.7874 0.4064)
			(stroke
				(width 0.1524)
				(type default)
			)
			(layer "B.SilkS")
		)
		(fp_line
			(start 0.7874 -0.4064)
			(end -0.7874 -0.4064)
			(stroke
				(width 0.1524)
				(type default)
			)
			(layer "B.SilkS")
		)
		(fp_line
			(start 0.7874 0.4064)
			(end 0.7874 -0.4064)
			(stroke
				(width 0.1524)
				(type default)
			)
			(layer "B.SilkS")
		)
		(fp_line
			(start -0.67945 -0.3048)
			(end -0.67945 0.3048)
			(stroke
				(width 0.1)
				(type default)
			)
			(layer "B.Fab")
		)
		(fp_line
			(start -0.67945 0.3048)
			(end -0.120396 0.3048)
			(stroke
				(width 0.1)
				(type default)
			)
			(layer "B.Fab")
		)
		(fp_line
			(start -0.12065 -0.3048)
			(end -0.67945 -0.3048)
			(stroke
				(width 0.1)
				(type default)
			)
			(layer "B.Fab")
		)
		(fp_line
			(start -0.12065 -0.2794)
			(end -0.12065 -0.3048)
			(stroke
				(width 0.1)
				(type default)
			)
			(layer "B.Fab")
		)
		(fp_line
			(start -0.120396 0.2794)
			(end 0.12065 0.2794)
			(stroke
				(width 0.1)
				(type default)
			)
			(layer "B.Fab")
		)
		(fp_line
			(start -0.120396 0.3048)
			(end -0.120396 0.2794)
			(stroke
				(width 0.1)
				(type default)
			)
			(layer "B.Fab")
		)
		(fp_line
			(start 0.12065 -0.305054)
			(end 0.12065 -0.2794)
			(stroke
				(width 0.1)
				(type default)
			)
			(layer "B.Fab")
		)
		(fp_line
			(start 0.12065 -0.2794)
			(end -0.12065 -0.2794)
			(stroke
				(width 0.1)
				(type default)
			)
			(layer "B.Fab")
		)
		(fp_line
			(start 0.12065 0.2794)
			(end 0.12065 0.3048)
			(stroke
				(width 0.1)
				(type default)
			)
			(layer "B.Fab")
		)
		(fp_line
			(start 0.12065 0.3048)
			(end 0.67945 0.3048)
			(stroke
				(width 0.1)
				(type default)
			)
			(layer "B.Fab")
		)
		(fp_line
			(start 0.67945 -0.305054)
			(end 0.12065 -0.305054)
			(stroke
				(width 0.1)
				(type default)
			)
			(layer "B.Fab")
		)
		(fp_line
			(start 0.67945 0.3048)
			(end 0.67945 -0.305054)
			(stroke
				(width 0.1)
				(type default)
			)
			(layer "B.Fab")
		)
		(pad "1" smd circle
			(at 0.40005 0 180)
			(size 0 0)
			(layers "B.Cu" "B.Mask" "B.Paste")
			(net "PVDD11_S3_P0")
		)
		(pad "2" smd circle
			(at -0.40005 0 180)
			(size 0 0)
			(layers "B.Cu" "B.Mask" "B.Paste")
			(net "GND")
		)
	)
)
